(kicad_pcb
	(version 20260206)
	(generator "pcbnew")
	(generator_version "10.0")
	(general
		(thickness 1.6)
		(legacy_teardrops no)
	)
	(paper "A4")
	(title_block
		(title "m-2 — Lightning_M.2_BRD.brd")
		(comment 1 "Lightning (Wiwynn / Facebook NVMe JBOF) / footprints 131-137 of 157")
	)
	(layers
		(0 "F.Cu" signal "TOP")
		(4 "In1.Cu" signal "L2GND")
		(6 "In2.Cu" signal "L3")
		(8 "In3.Cu" signal "L4GND")
		(10 "In4.Cu" signal "L5GND")
		(12 "In5.Cu" signal "L6")
		(14 "In6.Cu" signal "L7GND")
		(2 "B.Cu" signal "BOTTOM")
		(9 "F.Adhes" user "F.Adhesive")
		(11 "B.Adhes" user "B.Adhesive")
		(13 "F.Paste" user "Package Geometry/Pastemask Top")
		(15 "B.Paste" user "Package Geometry/Pastemask Bottom")
		(5 "F.SilkS" user "Ref Des/Silkscreen Top")
		(7 "B.SilkS" user "Ref Des/Silkscreen Bottom")
		(1 "F.Mask" user "Board Geometry/Soldermask Top")
		(3 "B.Mask" user "Board Geometry/Soldermask Bottom")
		(17 "Dwgs.User" user "User.Drawings")
		(19 "Cmts.User" user "User.Comments")
		(21 "Eco1.User" user "User.Eco1")
		(23 "Eco2.User" user "User.Eco2")
		(25 "Edge.Cuts" user "Board Geometry/Outline")
		(27 "Margin" user)
		(31 "F.CrtYd" user "Package Geometry/Place Bound Top")
		(29 "B.CrtYd" user "Package Geometry/Place Bound Bottom")
		(35 "F.Fab" user "Ref Des/Assembly Top")
		(33 "B.Fab" user "Ref Des/Assembly Bottom")
	)
	(footprint ""
		(layer "B.Cu")
		(at 52.705 -78.613 90)
		(property "Reference" "PR25"
			(at 0 0 90)
			(layer "B.SilkS")
			(hide yes)
			(effects
				(font
					(size 1.27 1.27)
				)
				(justify mirror)
			)
		)
		(property "Value" "10KR2F-2-GP"
			(at -0.064008 -3.993896 90)
			(unlocked yes)
			(layer "B.Fab")
			(hide yes)
			(effects
				(font
					(size 1.016 1.016)
					(thickness 0.1524)
				)
				(justify mirror)
			)
		)
		(property "Device Type" "R402H16"
			(at -0.064008 -5.517896 90)
			(unlocked yes)
			(layer "B.Fab")
			(hide yes)
			(effects
				(font
					(size 1.016 1.016)
					(thickness 0.1524)
				)
				(justify mirror)
			)
		)
		(duplicate_pad_numbers_are_jumpers no)
		(fp_line
			(start 0.508 -0.9398)
			(end 0.508 0.9398)
			(stroke
				(width 0.1524)
				(type default)
			)
			(layer "B.SilkS")
		)
		(fp_line
			(start -0.508 -0.9398)
			(end 0.508 -0.9398)
			(stroke
				(width 0.1524)
				(type default)
			)
			(layer "B.SilkS")
		)
		(fp_rect
			(start 0.508 0.9398)
			(end -0.508 -0.9398)
			(stroke
				(width 0)
				(type default)
			)
			(fill no)
			(layer "B.CrtYd")
		)
		(fp_rect
			(start 0.508 0.9398)
			(end -0.508 -0.9398)
			(stroke
				(width 0)
				(type default)
			)
			(fill no)
			(layer "B.Fab")
		)
		(pad "1" smd custom
			(at 0 -0.4445 270)
			(size 0.1397 0.1397)
			(layers "B.Cu" "B.Mask" "B.Paste")
			(net "P3V3_DEV_PWRGD")
			(options
				(clearance outline)
				(anchor circle)
			)
			(primitives
				(gr_poly
					(pts
						(arc
							(start -0.1778 0.2794)
							(mid -0.249642 0.249642)
							(end -0.2794 0.1778)
						)
						(arc
							(start -0.2794 -0.1778)
							(mid -0.249642 -0.249642)
							(end -0.1778 -0.2794)
						)
						(arc
							(start 0.1778 -0.2794)
							(mid 0.249642 -0.249642)
							(end 0.2794 -0.1778)
						)
						(arc
							(start 0.2794 0.1778)
							(mid 0.249642 0.249642)
							(end 0.1778 0.2794)
						)
					)
					(width 0)
					(fill yes)
				)
			)
		)
		(pad "2" smd custom
			(at 0 0.4445 270)
			(size 0.1397 0.1397)
			(layers "B.Cu" "B.Mask" "B.Paste")
			(net "P3V3_DEV_VREG")
			(options
				(clearance outline)
				(anchor circle)
			)
			(primitives
				(gr_poly
					(pts
						(arc
							(start -0.1778 0.2794)
							(mid -0.249642 0.249642)
							(end -0.2794 0.1778)
						)
						(arc
							(start -0.2794 -0.1778)
							(mid -0.249642 -0.249642)
							(end -0.1778 -0.2794)
						)
						(arc
							(start 0.1778 -0.2794)
							(mid 0.249642 -0.249642)
							(end 0.2794 -0.1778)
						)
						(arc
							(start 0.2794 0.1778)
							(mid 0.249642 0.249642)
							(end 0.1778 0.2794)
						)
					)
					(width 0)
					(fill yes)
				)
			)
		)
	)
	(footprint ""
		(layer "B.Cu")
		(at 60.579 -62.738 -90)
		(property "Reference" "C16"
			(at 0 0 90)
			(layer "B.SilkS")
			(hide yes)
			(effects
				(font
					(size 1.27 1.27)
				)
				(justify mirror)
			)
		)
		(property "Value" "SC10U6D3V5KX-4GP"
			(at 0.0762 -6.1214 270)
			(unlocked yes)
			(layer "B.Fab")
			(hide yes)
			(effects
				(font
					(size 1.016 1.016)
					(thickness 0.1524)
				)
				(justify mirror)
			)
		)
		(property "Device Type" "C805H58"
			(at 0.0762 -8.1534 270)
			(unlocked yes)
			(layer "B.Fab")
			(hide yes)
			(effects
				(font
					(size 1.016 1.016)
					(thickness 0.1524)
				)
				(justify mirror)
			)
		)
		(duplicate_pad_numbers_are_jumpers no)
		(fp_line
			(start -0.635 0)
			(end 0.635 0)
			(stroke
				(width 0.508)
				(type default)
			)
			(layer "B.SilkS")
		)
		(fp_rect
			(start 0.9652 1.778)
			(end -0.9652 -1.778)
			(stroke
				(width 0)
				(type default)
			)
			(fill no)
			(layer "B.CrtYd")
		)
		(fp_poly
			(pts
				(xy 0.9652 -1.778) (xy -0.9652 -1.778) (xy -0.9652 1.778) (xy 0.9652 1.778)
			)
			(stroke
				(width 0)
				(type default)
			)
			(fill no)
			(layer "B.Fab")
		)
		(pad "1" smd rect
			(at 0 -0.9652 90)
			(size 1.397 1.143)
			(layers "B.Cu" "B.Mask" "B.Paste")
			(net "P3V3_PWR")
		)
		(pad "2" smd rect
			(at 0 0.9652 90)
			(size 1.397 1.143)
			(layers "B.Cu" "B.Mask" "B.Paste")
			(net "GND")
		)
	)
	(footprint ""
		(layer "B.Cu")
		(at 65.151 -24.511 -90)
		(property "Reference" "R37"
			(at 0 0 90)
			(layer "B.SilkS")
			(hide yes)
			(effects
				(font
					(size 1.27 1.27)
				)
				(justify mirror)
			)
		)
		(property "Value" "47KR2F-GP"
			(at -0.064008 -3.993896 270)
			(unlocked yes)
			(layer "B.Fab")
			(hide yes)
			(effects
				(font
					(size 1.016 1.016)
					(thickness 0.1524)
				)
				(justify mirror)
			)
		)
		(property "Device Type" "R402H16"
			(at -0.064008 -5.517896 270)
			(unlocked yes)
			(layer "B.Fab")
			(hide yes)
			(effects
				(font
					(size 1.016 1.016)
					(thickness 0.1524)
				)
				(justify mirror)
			)
		)
		(duplicate_pad_numbers_are_jumpers no)
		(fp_line
			(start -0.508 -0.9398)
			(end 0.508 -0.9398)
			(stroke
				(width 0.1524)
				(type default)
			)
			(layer "B.SilkS")
		)
		(fp_line
			(start 0.508 -0.9398)
			(end 0.508 0.9398)
			(stroke
				(width 0.1524)
				(type default)
			)
			(layer "B.SilkS")
		)
		(fp_rect
			(start 0.508 0.9398)
			(end -0.508 -0.9398)
			(stroke
				(width 0)
				(type default)
			)
			(fill no)
			(layer "B.CrtYd")
		)
		(fp_rect
			(start 0.508 0.9398)
			(end -0.508 -0.9398)
			(stroke
				(width 0)
				(type default)
			)
			(fill no)
			(layer "B.Fab")
		)
		(pad "1" smd custom
			(at 0 -0.4445 90)
			(size 0.1397 0.1397)
			(layers "B.Cu" "B.Mask" "B.Paste")
			(net "Z50_SSD_B1_ALERT#")
			(options
				(clearance outline)
				(anchor circle)
			)
			(primitives
				(gr_poly
					(pts
						(arc
							(start -0.1778 0.2794)
							(mid -0.249642 0.249642)
							(end -0.2794 0.1778)
						)
						(arc
							(start -0.2794 -0.1778)
							(mid -0.249642 -0.249642)
							(end -0.1778 -0.2794)
						)
						(arc
							(start 0.1778 -0.2794)
							(mid 0.249642 -0.249642)
							(end 0.2794 -0.1778)
						)
						(arc
							(start 0.2794 0.1778)
							(mid 0.249642 0.249642)
							(end 0.1778 0.2794)
						)
					)
					(width 0)
					(fill yes)
				)
			)
		)
		(pad "2" smd custom
			(at 0 0.4445 90)
			(size 0.1397 0.1397)
			(layers "B.Cu" "B.Mask" "B.Paste")
			(net "P1V8_PWR")
			(options
				(clearance outline)
				(anchor circle)
			)
			(primitives
				(gr_poly
					(pts
						(arc
							(start -0.1778 0.2794)
							(mid -0.249642 0.249642)
							(end -0.2794 0.1778)
						)
						(arc
							(start -0.2794 -0.1778)
							(mid -0.249642 -0.249642)
							(end -0.1778 -0.2794)
						)
						(arc
							(start 0.1778 -0.2794)
							(mid 0.249642 -0.249642)
							(end 0.2794 -0.1778)
						)
						(arc
							(start 0.2794 0.1778)
							(mid 0.249642 0.249642)
							(end 0.1778 0.2794)
						)
					)
					(width 0)
					(fill yes)
				)
			)
		)
	)
	(footprint ""
		(layer "B.Cu")
		(at 65.151 -50.038 90)
		(property "Reference" "R43"
			(at 0 0 90)
			(layer "B.SilkS")
			(hide yes)
			(effects
				(font
					(size 1.27 1.27)
				)
				(justify mirror)
			)
		)
		(property "Value" "4K7R2F-GP"
			(at -0.064008 -3.993896 90)
			(unlocked yes)
			(layer "B.Fab")
			(hide yes)
			(effects
				(font
					(size 1.016 1.016)
					(thickness 0.1524)
				)
				(justify mirror)
			)
		)
		(property "Device Type" "R402H16"
			(at -0.064008 -5.517896 90)
			(unlocked yes)
			(layer "B.Fab")
			(hide yes)
			(effects
				(font
					(size 1.016 1.016)
					(thickness 0.1524)
				)
				(justify mirror)
			)
		)
		(duplicate_pad_numbers_are_jumpers no)
		(fp_line
			(start 0.508 -0.9398)
			(end 0.508 0.9398)
			(stroke
				(width 0.1524)
				(type default)
			)
			(layer "B.SilkS")
		)
		(fp_line
			(start -0.508 -0.9398)
			(end 0.508 -0.9398)
			(stroke
				(width 0.1524)
				(type default)
			)
			(layer "B.SilkS")
		)
		(fp_rect
			(start 0.508 0.9398)
			(end -0.508 -0.9398)
			(stroke
				(width 0)
				(type default)
			)
			(fill no)
			(layer "B.CrtYd")
		)
		(fp_rect
			(start 0.508 0.9398)
			(end -0.508 -0.9398)
			(stroke
				(width 0)
				(type default)
			)
			(fill no)
			(layer "B.Fab")
		)
		(pad "1" smd custom
			(at 0 -0.4445 270)
			(size 0.1397 0.1397)
			(layers "B.Cu" "B.Mask" "B.Paste")
			(net "P3V3_PWR")
			(options
				(clearance outline)
				(anchor circle)
			)
			(primitives
				(gr_poly
					(pts
						(arc
							(start -0.1778 0.2794)
							(mid -0.249642 0.249642)
							(end -0.2794 0.1778)
						)
						(arc
							(start -0.2794 -0.1778)
							(mid -0.249642 -0.249642)
							(end -0.1778 -0.2794)
						)
						(arc
							(start 0.1778 -0.2794)
							(mid 0.249642 -0.249642)
							(end 0.2794 -0.1778)
						)
						(arc
							(start 0.2794 0.1778)
							(mid 0.249642 0.249642)
							(end 0.1778 0.2794)
						)
					)
					(width 0)
					(fill yes)
				)
			)
		)
		(pad "2" smd custom
			(at 0 0.4445 270)
			(size 0.1397 0.1397)
			(layers "B.Cu" "B.Mask" "B.Paste")
			(net "Z50_SSD_A1_CLKREQ#")
			(options
				(clearance outline)
				(anchor circle)
			)
			(primitives
				(gr_poly
					(pts
						(arc
							(start -0.1778 0.2794)
							(mid -0.249642 0.249642)
							(end -0.2794 0.1778)
						)
						(arc
							(start -0.2794 -0.1778)
							(mid -0.249642 -0.249642)
							(end -0.1778 -0.2794)
						)
						(arc
							(start 0.1778 -0.2794)
							(mid 0.249642 -0.249642)
							(end 0.2794 -0.1778)
						)
						(arc
							(start 0.2794 0.1778)
							(mid 0.249642 0.249642)
							(end 0.1778 0.2794)
						)
					)
					(width 0)
					(fill yes)
				)
			)
		)
	)
	(footprint ""
		(layer "B.Cu")
		(at 29.845 -86.233 180)
		(property "Reference" "R30"
			(at 0 0 0)
			(layer "B.SilkS")
			(hide yes)
			(effects
				(font
					(size 1.27 1.27)
				)
				(justify mirror)
			)
		)
		(property "Value" "47KR2F-GP"
			(at -0.064008 -3.993896 180)
			(unlocked yes)
			(layer "B.Fab")
			(hide yes)
			(effects
				(font
					(size 1.016 1.016)
					(thickness 0.1524)
				)
				(justify mirror)
			)
		)
		(property "Device Type" "R402H16"
			(at -0.064008 -5.517896 180)
			(unlocked yes)
			(layer "B.Fab")
			(hide yes)
			(effects
				(font
					(size 1.016 1.016)
					(thickness 0.1524)
				)
				(justify mirror)
			)
		)
		(duplicate_pad_numbers_are_jumpers no)
		(fp_line
			(start 0.508 -0.9398)
			(end 0.508 0.9398)
			(stroke
				(width 0.1524)
				(type default)
			)
			(layer "B.SilkS")
		)
		(fp_line
			(start -0.508 -0.9398)
			(end 0.508 -0.9398)
			(stroke
				(width 0.1524)
				(type default)
			)
			(layer "B.SilkS")
		)
		(fp_rect
			(start 0.508 0.9398)
			(end -0.508 -0.9398)
			(stroke
				(width 0)
				(type default)
			)
			(fill no)
			(layer "B.CrtYd")
		)
		(fp_rect
			(start 0.508 0.9398)
			(end -0.508 -0.9398)
			(stroke
				(width 0)
				(type default)
			)
			(fill no)
			(layer "B.Fab")
		)
		(pad "1" smd custom
			(at 0 -0.4445)
			(size 0.1397 0.1397)
			(layers "B.Cu" "B.Mask" "B.Paste")
			(net "Z50_SSD_B1_SMB_CLK_R")
			(options
				(clearance outline)
				(anchor circle)
			)
			(primitives
				(gr_poly
					(pts
						(arc
							(start -0.1778 0.2794)
							(mid -0.249642 0.249642)
							(end -0.2794 0.1778)
						)
						(arc
							(start -0.2794 -0.1778)
							(mid -0.249642 -0.249642)
							(end -0.1778 -0.2794)
						)
						(arc
							(start 0.1778 -0.2794)
							(mid 0.249642 -0.249642)
							(end 0.2794 -0.1778)
						)
						(arc
							(start 0.2794 0.1778)
							(mid 0.249642 0.249642)
							(end 0.1778 0.2794)
						)
					)
					(width 0)
					(fill yes)
				)
			)
		)
		(pad "2" smd custom
			(at 0 0.4445)
			(size 0.1397 0.1397)
			(layers "B.Cu" "B.Mask" "B.Paste")
			(net "P3V3_DPB")
			(options
				(clearance outline)
				(anchor circle)
			)
			(primitives
				(gr_poly
					(pts
						(arc
							(start -0.1778 0.2794)
							(mid -0.249642 0.249642)
							(end -0.2794 0.1778)
						)
						(arc
							(start -0.2794 -0.1778)
							(mid -0.249642 -0.249642)
							(end -0.1778 -0.2794)
						)
						(arc
							(start 0.1778 -0.2794)
							(mid 0.249642 -0.249642)
							(end 0.2794 -0.1778)
						)
						(arc
							(start 0.2794 0.1778)
							(mid 0.249642 0.249642)
							(end 0.1778 0.2794)
						)
					)
					(width 0)
					(fill yes)
				)
			)
		)
	)
	(footprint ""
		(layer "B.Cu")
		(at 53.594 -81.28 90)
		(property "Reference" "PC40"
			(at 0 0 90)
			(layer "B.SilkS")
			(hide yes)
			(effects
				(font
					(size 1.27 1.27)
				)
				(justify mirror)
			)
		)
		(property "Value" "SCD1U50V3KX-GP"
			(at 0 -2.8194 90)
			(unlocked yes)
			(layer "B.Fab")
			(hide yes)
			(effects
				(font
					(size 1.016 1.016)
					(thickness 0.1524)
				)
				(justify mirror)
			)
		)
		(property "Device Type" "C603H36"
			(at 0 -4.3434 90)
			(unlocked yes)
			(layer "B.Fab")
			(hide yes)
			(effects
				(font
					(size 1.016 1.016)
					(thickness 0.1524)
				)
				(justify mirror)
			)
		)
		(duplicate_pad_numbers_are_jumpers no)
		(fp_line
			(start -0.508 0)
			(end 0.508 0)
			(stroke
				(width 0.2032)
				(type default)
			)
			(layer "B.SilkS")
		)
		(fp_rect
			(start 0.5842 1.3335)
			(end -0.5842 -1.3335)
			(stroke
				(width 0)
				(type default)
			)
			(fill no)
			(layer "B.CrtYd")
		)
		(fp_rect
			(start 0.5842 1.3335)
			(end -0.5842 -1.3335)
			(stroke
				(width 0)
				(type default)
			)
			(fill no)
			(layer "B.Fab")
		)
		(pad "1" smd custom
			(at 0 -0.762 270)
			(size 0.2159 0.2159)
			(layers "B.Cu" "B.Mask" "B.Paste")
			(net "P3V3_DEV_VBST_RC")
			(options
				(clearance outline)
				(anchor circle)
			)
			(primitives
				(gr_poly
					(pts
						(arc
							(start -0.3302 0.4318)
							(mid -0.402042 0.402042)
							(end -0.4318 0.3302)
						)
						(arc
							(start -0.4318 -0.3302)
							(mid -0.402042 -0.402042)
							(end -0.3302 -0.4318)
						)
						(arc
							(start 0.3302 -0.4318)
							(mid 0.402042 -0.402042)
							(end 0.4318 -0.3302)
						)
						(arc
							(start 0.4318 0.3302)
							(mid 0.402042 0.402042)
							(end 0.3302 0.4318)
						)
					)
					(width 0)
					(fill yes)
				)
			)
		)
		(pad "2" smd custom
			(at 0 0.762 270)
			(size 0.2159 0.2159)
			(layers "B.Cu" "B.Mask" "B.Paste")
			(net "P3V3_DEV_LL")
			(options
				(clearance outline)
				(anchor circle)
			)
			(primitives
				(gr_poly
					(pts
						(arc
							(start -0.3302 0.4318)
							(mid -0.402042 0.402042)
							(end -0.4318 0.3302)
						)
						(arc
							(start -0.4318 -0.3302)
							(mid -0.402042 -0.402042)
							(end -0.3302 -0.4318)
						)
						(arc
							(start 0.3302 -0.4318)
							(mid 0.402042 -0.402042)
							(end 0.4318 -0.3302)
						)
						(arc
							(start 0.4318 0.3302)
							(mid 0.402042 0.402042)
							(end 0.3302 0.4318)
						)
					)
					(width 0)
					(fill yes)
				)
			)
		)
	)
	(footprint ""
		(layer "B.Cu")
		(at 24.511 -77.216)
		(property "Reference" "R63"
			(at 0 0 0)
			(layer "B.SilkS")
			(hide yes)
			(effects
				(font
					(size 1.27 1.27)
				)
				(justify mirror)
			)
		)
		(property "Value" "0R2J-2-GP"
			(at -0.064008 -3.993896 0)
			(unlocked yes)
			(layer "B.Fab")
			(hide yes)
			(effects
				(font
					(size 1.016 1.016)
					(thickness 0.1524)
				)
				(justify mirror)
			)
		)
		(property "Device Type" "R402H16"
			(at -0.064008 -5.517896 0)
			(unlocked yes)
			(layer "B.Fab")
			(hide yes)
			(effects
				(font
					(size 1.016 1.016)
					(thickness 0.1524)
				)
				(justify mirror)
			)
		)
		(duplicate_pad_numbers_are_jumpers no)
		(fp_line
			(start -0.508 -0.9398)
			(end 0.508 -0.9398)
			(stroke
				(width 0.1524)
				(type default)
			)
			(layer "B.SilkS")
		)
		(fp_line
			(start 0.508 -0.9398)
			(end 0.508 0.9398)
			(stroke
				(width 0.1524)
				(type default)
			)
			(layer "B.SilkS")
		)
		(fp_rect
			(start 0.508 0.9398)
			(end -0.508 -0.9398)
			(stroke
				(width 0)
				(type default)
			)
			(fill no)
			(layer "B.CrtYd")
		)
		(fp_rect
			(start 0.508 0.9398)
			(end -0.508 -0.9398)
			(stroke
				(width 0)
				(type default)
			)
			(fill no)
			(layer "B.Fab")
		)
		(pad "1" smd custom
			(at 0 -0.4445 180)
			(size 0.1397 0.1397)
			(layers "B.Cu" "B.Mask" "B.Paste")
			(net "Z50_SSD_A1_SMB_CLK_R")
			(options
				(clearance outline)
				(anchor circle)
			)
			(primitives
				(gr_poly
					(pts
						(arc
							(start -0.1778 0.2794)
							(mid -0.249642 0.249642)
							(end -0.2794 0.1778)
						)
						(arc
							(start -0.2794 -0.1778)
							(mid -0.249642 -0.249642)
							(end -0.1778 -0.2794)
						)
						(arc
							(start 0.1778 -0.2794)
							(mid 0.249642 -0.249642)
							(end 0.2794 -0.1778)
						)
						(arc
							(start 0.2794 0.1778)
							(mid 0.249642 0.249642)
							(end 0.1778 0.2794)
						)
					)
					(width 0)
					(fill yes)
				)
			)
		)
		(pad "2" smd custom
			(at 0 0.4445 180)
			(size 0.1397 0.1397)
			(layers "B.Cu" "B.Mask" "B.Paste")
			(net "Z50_SSD_A1_SMB_CLK")
			(options
				(clearance outline)
				(anchor circle)
			)
			(primitives
				(gr_poly
					(pts
						(arc
							(start -0.1778 0.2794)
							(mid -0.249642 0.249642)
							(end -0.2794 0.1778)
						)
						(arc
							(start -0.2794 -0.1778)
							(mid -0.249642 -0.249642)
							(end -0.1778 -0.2794)
						)
						(arc
							(start 0.1778 -0.2794)
							(mid 0.249642 -0.249642)
							(end 0.2794 -0.1778)
						)
						(arc
							(start 0.2794 0.1778)
							(mid 0.249642 0.249642)
							(end 0.1778 0.2794)
						)
					)
					(width 0)
					(fill yes)
				)
			)
		)
	)
)
